(kicad_pcb
	(version 20260206)
	(generator "pcbnew")
	(generator_version "10.0")
	(general
		(thickness 1.6)
		(legacy_teardrops no)
	)
	(paper "A4")
	(title_block
		(title "Bryce Canyon_LED_16347-1_OCP.brd")
		(comment 1 "Bryce Canyon / footprints 49-49 of 49")
	)
	(layers
		(0 "F.Cu" signal "TOP")
		(2 "B.Cu" signal "BOTTOM")
		(9 "F.Adhes" user "F.Adhesive")
		(11 "B.Adhes" user "B.Adhesive")
		(13 "F.Paste" user "Package Geometry/Pastemask Top")
		(15 "B.Paste" user "Package Geometry/Pastemask Bottom")
		(5 "F.SilkS" user "Ref Des/Silkscreen Top")
		(7 "B.SilkS" user "Ref Des/Silkscreen Bottom")
		(1 "F.Mask" user "Board Geometry/Soldermask Top")
		(3 "B.Mask" user "Board Geometry/Soldermask Bottom")
		(17 "Dwgs.User" user "User.Drawings")
		(19 "Cmts.User" user "User.Comments")
		(21 "Eco1.User" user "User.Eco1")
		(23 "Eco2.User" user "User.Eco2")
		(25 "Edge.Cuts" user "Board Geometry/Outline")
		(27 "Margin" user)
		(31 "F.CrtYd" user "Package Geometry/Place Bound Top")
		(29 "B.CrtYd" user "Package Geometry/Place Bound Bottom")
		(35 "F.Fab" user "Ref Des/Assembly Top")
		(33 "B.Fab" user "Ref Des/Assembly Bottom")
	)
	(footprint ""
		(layer "B.Cu")
		(at 142.0622 -5.715)
		(property "Reference" "Q10"
			(at 0 0 0)
			(layer "B.SilkS")
			(hide yes)
			(effects
				(font
					(size 1.27 1.27)
				)
				(justify mirror)
			)
		)
		(property "Value" "SSM3K324R-GP"
			(at -0.127 -8.9662 0)
			(unlocked yes)
			(layer "B.Fab")
			(hide yes)
			(effects
				(font
					(size 1.016 1.016)
					(thickness 0.1524)
				)
				(justify mirror)
			)
		)
		(property "Device Type" "SOT23DGS2D4H35"
			(at -0.127 -10.4902 0)
			(unlocked yes)
			(layer "B.Fab")
			(hide yes)
			(effects
				(font
					(size 1.016 1.016)
					(thickness 0.1524)
				)
				(justify mirror)
			)
		)
		(duplicate_pad_numbers_are_jumpers no)
		(fp_line
			(start -1.651 -1.778)
			(end 1.651 -1.778)
			(stroke
				(width 0.1524)
				(type default)
			)
			(layer "B.SilkS")
		)
		(fp_line
			(start -1.651 1.778)
			(end -1.651 -1.778)
			(stroke
				(width 0.1524)
				(type default)
			)
			(layer "B.SilkS")
		)
		(fp_line
			(start 1.651 -1.778)
			(end 1.651 1.778)
			(stroke
				(width 0.1524)
				(type default)
			)
			(layer "B.SilkS")
		)
		(fp_line
			(start 1.651 1.778)
			(end -1.651 1.778)
			(stroke
				(width 0.1524)
				(type default)
			)
			(layer "B.SilkS")
		)
		(fp_poly
			(pts
				(xy 1.778 1.8796) (xy 1.778 -1.8796) (xy -1.778 -1.8796) (xy -1.778 1.8796)
			)
			(stroke
				(width 0)
				(type default)
			)
			(fill no)
			(layer "B.CrtYd")
		)
		(fp_poly
			(pts
				(xy 1.778 1.8796) (xy 1.778 -1.8796) (xy -1.778 -1.8796) (xy -1.778 1.8796)
			)
			(stroke
				(width 0)
				(type default)
			)
			(fill no)
			(layer "B.Fab")
		)
		(pad "D" smd custom
			(at 0 -0.9525 180)
			(size 0.1905 0.1905)
			(layers "B.Cu" "B.Mask" "B.Paste")
			(net "DRV_ACT_28_34_N")
			(options
				(clearance outline)
				(anchor circle)
			)
			(primitives
				(gr_poly
					(pts
						(arc
							(start -0.1778 -0.5715)
							(mid -0.321484 -0.511984)
							(end -0.381 -0.3683)
						)
						(arc
							(start -0.381 0.3683)
							(mid -0.321484 0.511984)
							(end -0.1778 0.5715)
						)
						(arc
							(start 0.1778 0.5715)
							(mid 0.321484 0.511984)
							(end 0.381 0.3683)
						)
						(arc
							(start 0.381 -0.3683)
							(mid 0.321484 -0.511984)
							(end 0.1778 -0.5715)
						)
					)
					(width 0)
					(fill yes)
				)
			)
		)
		(pad "G" smd custom
			(at 0.98425 0.9525 180)
			(size 0.1905 0.1905)
			(layers "B.Cu" "B.Mask" "B.Paste")
			(net "DRIVE_A_28_34_ACT")
			(options
				(clearance outline)
				(anchor circle)
			)
			(primitives
				(gr_poly
					(pts
						(arc
							(start -0.1778 -0.5715)
							(mid -0.321484 -0.511984)
							(end -0.381 -0.3683)
						)
						(arc
							(start -0.381 0.3683)
							(mid -0.321484 0.511984)
							(end -0.1778 0.5715)
						)
						(arc
							(start 0.1778 0.5715)
							(mid 0.321484 0.511984)
							(end 0.381 0.3683)
						)
						(arc
							(start 0.381 -0.3683)
							(mid 0.321484 -0.511984)
							(end 0.1778 -0.5715)
						)
					)
					(width 0)
					(fill yes)
				)
			)
		)
		(pad "S" smd custom
			(at -0.98425 0.9525 180)
			(size 0.1905 0.1905)
			(layers "B.Cu" "B.Mask" "B.Paste")
			(net "GND")
			(options
				(clearance outline)
				(anchor circle)
			)
			(primitives
				(gr_poly
					(pts
						(arc
							(start -0.1778 -0.5715)
							(mid -0.321484 -0.511984)
							(end -0.381 -0.3683)
						)
						(arc
							(start -0.381 0.3683)
							(mid -0.321484 0.511984)
							(end -0.1778 0.5715)
						)
						(arc
							(start 0.1778 0.5715)
							(mid 0.321484 0.511984)
							(end 0.381 0.3683)
						)
						(arc
							(start 0.381 -0.3683)
							(mid 0.321484 -0.511984)
							(end 0.1778 -0.5715)
						)
					)
					(width 0)
					(fill yes)
				)
			)
		)
	)
)
